# T6G (Grand Teton) — schematic netlist excerpt (pin names and nets, part order shuffled) for the footprints in the layout excerpt that follows; sources: Cadence DE-HDL packaged netlist, KiCad conversion of 04192023_DAF0TMB3IC0_F0TG_MB_C_brd_V02_OCP.brd

C59  Q_CAP  100PF 50V 5% EMPTY  pkg 0402  page 257 : A = P12V_OCP_V3_2_ISENSE_MAM ; B = GND
PC2350  Q_CAP  1NF 50V 10% EMPTY  pkg 0402  page 264 : A = HSC_OCREF ; B = AGND_HSC

(kicad_pcb
	(version 20260206)
	(generator "pcbnew")
	(generator_version "10.0")
	(general
		(thickness 1.6)
		(legacy_teardrops no)
	)
	(paper "A4")
	(title_block
		(title "04192023_DAF0TMB3IC0_F0TG_MB_C_brd_V02_OCP.brd")
		(comment 1 "Grand Teton / footprints 603-604 of 8354")
	)
	(layers
		(0 "F.Cu" signal "TOP")
		(4 "In1.Cu" signal "GND")
		(6 "In2.Cu" signal "IN1")
		(8 "In3.Cu" signal "GND1")
		(10 "In4.Cu" signal "IN2")
		(12 "In5.Cu" signal "GND2")
		(14 "In6.Cu" signal "IN3")
		(16 "In7.Cu" signal "GND3")
		(18 "In8.Cu" signal "VCC")
		(20 "In9.Cu" signal "VCC1")
		(22 "In10.Cu" signal "GND4")
		(24 "In11.Cu" signal "IN4")
		(26 "In12.Cu" signal "GND5")
		(28 "In13.Cu" signal "IN5")
		(30 "In14.Cu" signal "GND6")
		(32 "In15.Cu" signal "IN6")
		(34 "In16.Cu" signal "GND7")
		(2 "B.Cu" signal "BOTTOM")
		(9 "F.Adhes" user "F.Adhesive")
		(11 "B.Adhes" user "B.Adhesive")
		(13 "F.Paste" user "Package Geometry/Pastemask Top")
		(15 "B.Paste" user "Package Geometry/Pastemask Bottom")
		(5 "F.SilkS" user "Ref Des/Silkscreen Top")
		(7 "B.SilkS" user "Ref Des/Silkscreen Bottom")
		(1 "F.Mask" user "Board Geometry/Soldermask Top")
		(3 "B.Mask" user "Board Geometry/Soldermask Bottom")
		(17 "Dwgs.User" user "User.Drawings")
		(19 "Cmts.User" user "User.Comments")
		(21 "Eco1.User" user "User.Eco1")
		(23 "Eco2.User" user "User.Eco2")
		(25 "Edge.Cuts" user "Board Geometry/Outline")
		(27 "Margin" user)
		(31 "F.CrtYd" user "Package Geometry/Place Bound Top")
		(29 "B.CrtYd" user "Package Geometry/Place Bound Bottom")
		(35 "F.Fab" user "Ref Des/Assembly Top")
		(33 "B.Fab" user "Ref Des/Assembly Bottom")
	)
	(footprint ""
		(layer "F.Cu")
		(at 215.4301 -398.940782 180)
		(property "Reference" "PC2350"
			(at 0 0 180)
			(layer "F.SilkS")
			(hide yes)
			(effects
				(font
					(size 1.27 1.27)
				)
			)
		)
		(property "Value" ""
			(at 0 0 180)
			(layer "F.Fab")
			(effects
				(font
					(size 1.27 1.27)
				)
			)
		)
		(duplicate_pad_numbers_are_jumpers no)
		(fp_line
			(start 0.7874 0.4064)
			(end -0.7874 0.4064)
			(stroke
				(width 0.1524)
				(type default)
			)
			(layer "F.SilkS")
		)
		(fp_line
			(start 0.7874 -0.4064)
			(end 0.7874 0.4064)
			(stroke
				(width 0.1524)
				(type default)
			)
			(layer "F.SilkS")
		)
		(fp_line
			(start -0.7874 0.4064)
			(end -0.7874 -0.4064)
			(stroke
				(width 0.1524)
				(type default)
			)
			(layer "F.SilkS")
		)
		(fp_line
			(start -0.7874 -0.4064)
			(end 0.7874 -0.4064)
			(stroke
				(width 0.1524)
				(type default)
			)
			(layer "F.SilkS")
		)
		(fp_line
			(start 0.67945 0.3048)
			(end 0.120396 0.3048)
			(stroke
				(width 0.1)
				(type default)
			)
			(layer "F.Fab")
		)
		(fp_line
			(start 0.67945 -0.3048)
			(end 0.67945 0.3048)
			(stroke
				(width 0.1)
				(type default)
			)
			(layer "F.Fab")
		)
		(fp_line
			(start 0.12065 -0.2794)
			(end 0.12065 -0.3048)
			(stroke
				(width 0.1)
				(type default)
			)
			(layer "F.Fab")
		)
		(fp_line
			(start 0.12065 -0.3048)
			(end 0.67945 -0.3048)
			(stroke
				(width 0.1)
				(type default)
			)
			(layer "F.Fab")
		)
		(fp_line
			(start 0.120396 0.3048)
			(end 0.120396 0.2794)
			(stroke
				(width 0.1)
				(type default)
			)
			(layer "F.Fab")
		)
		(fp_line
			(start 0.120396 0.2794)
			(end -0.12065 0.2794)
			(stroke
				(width 0.1)
				(type default)
			)
			(layer "F.Fab")
		)
		(fp_line
			(start -0.12065 0.3048)
			(end -0.67945 0.3048)
			(stroke
				(width 0.1)
				(type default)
			)
			(layer "F.Fab")
		)
		(fp_line
			(start -0.12065 0.2794)
			(end -0.12065 0.3048)
			(stroke
				(width 0.1)
				(type default)
			)
			(layer "F.Fab")
		)
		(fp_line
			(start -0.12065 -0.2794)
			(end 0.12065 -0.2794)
			(stroke
				(width 0.1)
				(type default)
			)
			(layer "F.Fab")
		)
		(fp_line
			(start -0.12065 -0.305054)
			(end -0.12065 -0.2794)
			(stroke
				(width 0.1)
				(type default)
			)
			(layer "F.Fab")
		)
		(fp_line
			(start -0.67945 0.3048)
			(end -0.67945 -0.305054)
			(stroke
				(width 0.1)
				(type default)
			)
			(layer "F.Fab")
		)
		(fp_line
			(start -0.67945 -0.305054)
			(end -0.12065 -0.305054)
			(stroke
				(width 0.1)
				(type default)
			)
			(layer "F.Fab")
		)
		(pad "1" smd circle
			(at -0.40005 0 180)
			(size 0 0)
			(layers "F.Cu" "F.Mask" "F.Paste")
			(net "HSC_OCREF")
		)
		(pad "2" smd circle
			(at 0.40005 0 180)
			(size 0 0)
			(layers "F.Cu" "F.Mask" "F.Paste")
			(net "AGND_HSC")
		)
	)
	(footprint ""
		(layer "F.Cu")
		(at 315.771022 -32.572706 180)
		(property "Reference" "C59"
			(at 0 0 180)
			(layer "F.SilkS")
			(hide yes)
			(effects
				(font
					(size 1.27 1.27)
				)
			)
		)
		(property "Value" ""
			(at 0 0 180)
			(layer "F.Fab")
			(effects
				(font
					(size 1.27 1.27)
				)
			)
		)
		(duplicate_pad_numbers_are_jumpers no)
		(fp_line
			(start 0.7874 0.4064)
			(end -0.7874 0.4064)
			(stroke
				(width 0.1524)
				(type default)
			)
			(layer "F.SilkS")
		)
		(fp_line
			(start 0.7874 -0.4064)
			(end 0.7874 0.4064)
			(stroke
				(width 0.1524)
				(type default)
			)
			(layer "F.SilkS")
		)
		(fp_line
			(start -0.7874 0.4064)
			(end -0.7874 -0.4064)
			(stroke
				(width 0.1524)
				(type default)
			)
			(layer "F.SilkS")
		)
		(fp_line
			(start -0.7874 -0.4064)
			(end 0.7874 -0.4064)
			(stroke
				(width 0.1524)
				(type default)
			)
			(layer "F.SilkS")
		)
		(fp_line
			(start 0.67945 0.3048)
			(end 0.120396 0.3048)
			(stroke
				(width 0.1)
				(type default)
			)
			(layer "F.Fab")
		)
		(fp_line
			(start 0.67945 -0.3048)
			(end 0.67945 0.3048)
			(stroke
				(width 0.1)
				(type default)
			)
			(layer "F.Fab")
		)
		(fp_line
			(start 0.12065 -0.2794)
			(end 0.12065 -0.3048)
			(stroke
				(width 0.1)
				(type default)
			)
			(layer "F.Fab")
		)
		(fp_line
			(start 0.12065 -0.3048)
			(end 0.67945 -0.3048)
			(stroke
				(width 0.1)
				(type default)
			)
			(layer "F.Fab")
		)
		(fp_line
			(start 0.120396 0.3048)
			(end 0.120396 0.2794)
			(stroke
				(width 0.1)
				(type default)
			)
			(layer "F.Fab")
		)
		(fp_line
			(start 0.120396 0.2794)
			(end -0.12065 0.2794)
			(stroke
				(width 0.1)
				(type default)
			)
			(layer "F.Fab")
		)
		(fp_line
			(start -0.12065 0.3048)
			(end -0.67945 0.3048)
			(stroke
				(width 0.1)
				(type default)
			)
			(layer "F.Fab")
		)
		(fp_line
			(start -0.12065 0.2794)
			(end -0.12065 0.3048)
			(stroke
				(width 0.1)
				(type default)
			)
			(layer "F.Fab")
		)
		(fp_line
			(start -0.12065 -0.2794)
			(end 0.12065 -0.2794)
			(stroke
				(width 0.1)
				(type default)
			)
			(layer "F.Fab")
		)
		(fp_line
			(start -0.12065 -0.305054)
			(end -0.12065 -0.2794)
			(stroke
				(width 0.1)
				(type default)
			)
			(layer "F.Fab")
		)
		(fp_line
			(start -0.67945 0.3048)
			(end -0.67945 -0.305054)
			(stroke
				(width 0.1)
				(type default)
			)
			(layer "F.Fab")
		)
		(fp_line
			(start -0.67945 -0.305054)
			(end -0.12065 -0.305054)
			(stroke
				(width 0.1)
				(type default)
			)
			(layer "F.Fab")
		)
		(pad "1" smd circle
			(at -0.40005 0 180)
			(size 0 0)
			(layers "F.Cu" "F.Mask" "F.Paste")
			(net "P12V_OCP_V3_2_ISENSE_MAM")
		)
		(pad "2" smd circle
			(at 0.40005 0 180)
			(size 0 0)
			(layers "F.Cu" "F.Mask" "F.Paste")
			(net "GND")
		)
	)
)
